(kicad_pcb
	(version 20260206)
	(generator "pcbnew")
	(generator_version "10.0")
	(general
		(thickness 1.6)
		(legacy_teardrops no)
	)
	(paper "A4")
	(title_block
		(title "01162023_DA0F0TEBIF0_F0T_Expander_BD_F_brd_V02_OCP.brd")
		(comment 1 "Grand Teton / footprints 3135-3140 of 9728")
	)
	(layers
		(0 "F.Cu" signal "TOP")
		(4 "In1.Cu" signal "GND")
		(6 "In2.Cu" signal "VCC")
		(8 "In3.Cu" signal "VCC1")
		(10 "In4.Cu" signal "GND1")
		(12 "In5.Cu" signal "IN1")
		(14 "In6.Cu" signal "GND2")
		(16 "In7.Cu" signal "IN2")
		(18 "In8.Cu" signal "GND3")
		(20 "In9.Cu" signal "IN3")
		(22 "In10.Cu" signal "GND4")
		(24 "In11.Cu" signal "IN4")
		(26 "In12.Cu" signal "GND5")
		(28 "In13.Cu" signal "IN5")
		(30 "In14.Cu" signal "GND6")
		(32 "In15.Cu" signal "IN6")
		(34 "In16.Cu" signal "GND7")
		(2 "B.Cu" signal "BOTTOM")
		(9 "F.Adhes" user "F.Adhesive")
		(11 "B.Adhes" user "B.Adhesive")
		(13 "F.Paste" user "Package Geometry/Pastemask Top")
		(15 "B.Paste" user "Package Geometry/Pastemask Bottom")
		(5 "F.SilkS" user "Ref Des/Silkscreen Top")
		(7 "B.SilkS" user "Ref Des/Silkscreen Bottom")
		(1 "F.Mask" user "Board Geometry/Soldermask Top")
		(3 "B.Mask" user "Board Geometry/Soldermask Bottom")
		(17 "Dwgs.User" user "User.Drawings")
		(19 "Cmts.User" user "User.Comments")
		(21 "Eco1.User" user "User.Eco1")
		(23 "Eco2.User" user "User.Eco2")
		(25 "Edge.Cuts" user "Board Geometry/Outline")
		(27 "Margin" user)
		(31 "F.CrtYd" user "Package Geometry/Place Bound Top")
		(29 "B.CrtYd" user "Package Geometry/Place Bound Bottom")
		(35 "F.Fab" user "Ref Des/Assembly Top")
		(33 "B.Fab" user "Ref Des/Assembly Bottom")
	)
	(footprint ""
		(layer "F.Cu")
		(at 402.25218 -343.952322 90)
		(property "Reference" "C732"
			(at 0 0 90)
			(layer "F.SilkS")
			(hide yes)
			(effects
				(font
					(size 1.27 1.27)
				)
			)
		)
		(property "Value" ""
			(at 0 0 90)
			(layer "F.Fab")
			(effects
				(font
					(size 1.27 1.27)
				)
			)
		)
		(duplicate_pad_numbers_are_jumpers no)
		(fp_line
			(start 0.299974 -0.150114)
			(end 0.299974 0.150114)
			(stroke
				(width 0.1)
				(type default)
			)
			(layer "F.Fab")
		)
		(fp_line
			(start -0.299974 -0.150114)
			(end 0.299974 -0.150114)
			(stroke
				(width 0.1)
				(type default)
			)
			(layer "F.Fab")
		)
		(fp_line
			(start 0.299974 0.150114)
			(end -0.299974 0.150114)
			(stroke
				(width 0.1)
				(type default)
			)
			(layer "F.Fab")
		)
		(fp_line
			(start -0.299974 0.150114)
			(end -0.299974 -0.150114)
			(stroke
				(width 0.1)
				(type default)
			)
			(layer "F.Fab")
		)
		(pad "1" smd rect
			(at -0.2667 0 90)
			(size 0.3048 0.381)
			(layers "F.Cu" "F.Mask" "F.Paste")
			(net "P5E_PEX3_STN5_TX_DP<94>")
		)
		(pad "2" smd rect
			(at 0.2667 0 90)
			(size 0.3048 0.381)
			(layers "F.Cu" "F.Mask" "F.Paste")
			(net "P5E_PEX3_STN5_TX_C_DP<94>")
		)
	)
	(footprint ""
		(layer "F.Cu")
		(at 100.955094 -397.512286 -90)
		(property "Reference" "R5452"
			(at 0 0 270)
			(layer "F.SilkS")
			(hide yes)
			(effects
				(font
					(size 1.27 1.27)
				)
			)
		)
		(property "Value" ""
			(at 0 0 270)
			(layer "F.Fab")
			(effects
				(font
					(size 1.27 1.27)
				)
			)
		)
		(duplicate_pad_numbers_are_jumpers no)
		(fp_line
			(start -0.7874 0.4064)
			(end -0.7874 -0.4064)
			(stroke
				(width 0.1524)
				(type default)
			)
			(layer "F.SilkS")
		)
		(fp_line
			(start 0.7874 0.4064)
			(end -0.7874 0.4064)
			(stroke
				(width 0.1524)
				(type default)
			)
			(layer "F.SilkS")
		)
		(fp_line
			(start -0.7874 -0.4064)
			(end 0.7874 -0.4064)
			(stroke
				(width 0.1524)
				(type default)
			)
			(layer "F.SilkS")
		)
		(fp_line
			(start 0.7874 -0.4064)
			(end 0.7874 0.4064)
			(stroke
				(width 0.1524)
				(type default)
			)
			(layer "F.SilkS")
		)
		(fp_line
			(start -0.67945 0.3048)
			(end -0.67945 -0.305054)
			(stroke
				(width 0.1)
				(type default)
			)
			(layer "F.Fab")
		)
		(fp_line
			(start -0.12065 0.3048)
			(end -0.67945 0.3048)
			(stroke
				(width 0.1)
				(type default)
			)
			(layer "F.Fab")
		)
		(fp_line
			(start 0.120396 0.3048)
			(end 0.120396 0.2794)
			(stroke
				(width 0.1)
				(type default)
			)
			(layer "F.Fab")
		)
		(fp_line
			(start 0.67945 0.3048)
			(end 0.120396 0.3048)
			(stroke
				(width 0.1)
				(type default)
			)
			(layer "F.Fab")
		)
		(fp_line
			(start -0.12065 0.2794)
			(end -0.12065 0.3048)
			(stroke
				(width 0.1)
				(type default)
			)
			(layer "F.Fab")
		)
		(fp_line
			(start 0.120396 0.2794)
			(end -0.12065 0.2794)
			(stroke
				(width 0.1)
				(type default)
			)
			(layer "F.Fab")
		)
		(fp_line
			(start -0.12065 -0.2794)
			(end 0.12065 -0.2794)
			(stroke
				(width 0.1)
				(type default)
			)
			(layer "F.Fab")
		)
		(fp_line
			(start 0.12065 -0.2794)
			(end 0.12065 -0.3048)
			(stroke
				(width 0.1)
				(type default)
			)
			(layer "F.Fab")
		)
		(fp_line
			(start 0.12065 -0.3048)
			(end 0.67945 -0.3048)
			(stroke
				(width 0.1)
				(type default)
			)
			(layer "F.Fab")
		)
		(fp_line
			(start 0.67945 -0.3048)
			(end 0.67945 0.3048)
			(stroke
				(width 0.1)
				(type default)
			)
			(layer "F.Fab")
		)
		(fp_line
			(start -0.67945 -0.305054)
			(end -0.12065 -0.305054)
			(stroke
				(width 0.1)
				(type default)
			)
			(layer "F.Fab")
		)
		(fp_line
			(start -0.12065 -0.305054)
			(end -0.12065 -0.2794)
			(stroke
				(width 0.1)
				(type default)
			)
			(layer "F.Fab")
		)
		(pad "1" smd circle
			(at -0.40005 0 270)
			(size 0 0)
			(layers "F.Cu" "F.Mask" "F.Paste")
			(net "P3V3_AUX")
		)
		(pad "2" smd circle
			(at 0.40005 0 270)
			(size 0 0)
			(layers "F.Cu" "F.Mask" "F.Paste")
			(net "BIC_USB_HUB_OVCUR3")
		)
	)
	(footprint ""
		(layer "F.Cu")
		(at 86.218522 -356.244906 90)
		(property "Reference" "C153"
			(at 0 0 90)
			(layer "F.SilkS")
			(hide yes)
			(effects
				(font
					(size 1.27 1.27)
				)
			)
		)
		(property "Value" ""
			(at 0 0 90)
			(layer "F.Fab")
			(effects
				(font
					(size 1.27 1.27)
				)
			)
		)
		(duplicate_pad_numbers_are_jumpers no)
		(fp_line
			(start 0.299974 -0.150114)
			(end 0.299974 0.150114)
			(stroke
				(width 0.1)
				(type default)
			)
			(layer "F.Fab")
		)
		(fp_line
			(start -0.299974 -0.150114)
			(end 0.299974 -0.150114)
			(stroke
				(width 0.1)
				(type default)
			)
			(layer "F.Fab")
		)
		(fp_line
			(start 0.299974 0.150114)
			(end -0.299974 0.150114)
			(stroke
				(width 0.1)
				(type default)
			)
			(layer "F.Fab")
		)
		(fp_line
			(start -0.299974 0.150114)
			(end -0.299974 -0.150114)
			(stroke
				(width 0.1)
				(type default)
			)
			(layer "F.Fab")
		)
		(pad "1" smd rect
			(at -0.2667 0 90)
			(size 0.3048 0.381)
			(layers "F.Cu" "F.Mask" "F.Paste")
			(net "P5E_PEX0_STN6_TX_DP<99>")
		)
		(pad "2" smd rect
			(at 0.2667 0 90)
			(size 0.3048 0.381)
			(layers "F.Cu" "F.Mask" "F.Paste")
			(net "P5E_PEX0_STN6_TX_C_DP<99>")
		)
	)
	(footprint ""
		(layer "F.Cu")
		(at 422.185592 -25.1587 -90)
		(property "Reference" "R5748"
			(at 0 0 270)
			(layer "F.SilkS")
			(hide yes)
			(effects
				(font
					(size 1.27 1.27)
				)
			)
		)
		(property "Value" ""
			(at 0 0 270)
			(layer "F.Fab")
			(effects
				(font
					(size 1.27 1.27)
				)
			)
		)
		(duplicate_pad_numbers_are_jumpers no)
		(fp_line
			(start -0.7874 0.4064)
			(end -0.7874 -0.4064)
			(stroke
				(width 0.1524)
				(type default)
			)
			(layer "F.SilkS")
		)
		(fp_line
			(start 0.7874 0.4064)
			(end -0.7874 0.4064)
			(stroke
				(width 0.1524)
				(type default)
			)
			(layer "F.SilkS")
		)
		(fp_line
			(start -0.7874 -0.4064)
			(end 0.7874 -0.4064)
			(stroke
				(width 0.1524)
				(type default)
			)
			(layer "F.SilkS")
		)
		(fp_line
			(start 0.7874 -0.4064)
			(end 0.7874 0.4064)
			(stroke
				(width 0.1524)
				(type default)
			)
			(layer "F.SilkS")
		)
		(fp_line
			(start -0.67945 0.3048)
			(end -0.67945 -0.305054)
			(stroke
				(width 0.1)
				(type default)
			)
			(layer "F.Fab")
		)
		(fp_line
			(start -0.12065 0.3048)
			(end -0.67945 0.3048)
			(stroke
				(width 0.1)
				(type default)
			)
			(layer "F.Fab")
		)
		(fp_line
			(start 0.120396 0.3048)
			(end 0.120396 0.2794)
			(stroke
				(width 0.1)
				(type default)
			)
			(layer "F.Fab")
		)
		(fp_line
			(start 0.67945 0.3048)
			(end 0.120396 0.3048)
			(stroke
				(width 0.1)
				(type default)
			)
			(layer "F.Fab")
		)
		(fp_line
			(start -0.12065 0.2794)
			(end -0.12065 0.3048)
			(stroke
				(width 0.1)
				(type default)
			)
			(layer "F.Fab")
		)
		(fp_line
			(start 0.120396 0.2794)
			(end -0.12065 0.2794)
			(stroke
				(width 0.1)
				(type default)
			)
			(layer "F.Fab")
		)
		(fp_line
			(start -0.12065 -0.2794)
			(end 0.12065 -0.2794)
			(stroke
				(width 0.1)
				(type default)
			)
			(layer "F.Fab")
		)
		(fp_line
			(start 0.12065 -0.2794)
			(end 0.12065 -0.3048)
			(stroke
				(width 0.1)
				(type default)
			)
			(layer "F.Fab")
		)
		(fp_line
			(start 0.12065 -0.3048)
			(end 0.67945 -0.3048)
			(stroke
				(width 0.1)
				(type default)
			)
			(layer "F.Fab")
		)
		(fp_line
			(start 0.67945 -0.3048)
			(end 0.67945 0.3048)
			(stroke
				(width 0.1)
				(type default)
			)
			(layer "F.Fab")
		)
		(fp_line
			(start -0.67945 -0.305054)
			(end -0.12065 -0.305054)
			(stroke
				(width 0.1)
				(type default)
			)
			(layer "F.Fab")
		)
		(fp_line
			(start -0.12065 -0.305054)
			(end -0.12065 -0.2794)
			(stroke
				(width 0.1)
				(type default)
			)
			(layer "F.Fab")
		)
		(pad "1" smd circle
			(at -0.40005 0 270)
			(size 0 0)
			(layers "F.Cu" "F.Mask" "F.Paste")
			(net "SSD14_LED_ISO_N")
		)
		(pad "2" smd circle
			(at 0.40005 0 270)
			(size 0 0)
			(layers "F.Cu" "F.Mask" "F.Paste")
			(net "SSD14_LED_ISO_R_N")
		)
	)
	(footprint ""
		(layer "F.Cu")
		(at 141.70533 -189.778132)
		(property "Reference" "U440"
			(at -3.61315 1.373632 0)
			(unlocked yes)
			(layer "F.SilkS")
			(effects
				(font
					(size 0.7874 0.5842)
					(thickness 0.1524)
				)
			)
		)
		(property "Value" ""
			(at 0 0 0)
			(layer "F.Fab")
			(effects
				(font
					(size 1.27 1.27)
				)
			)
		)
		(duplicate_pad_numbers_are_jumpers no)
		(fp_line
			(start -1.7272 1.1176)
			(end -1.7272 -1.1176)
			(stroke
				(width 0.1524)
				(type default)
			)
			(layer "F.SilkS")
		)
		(fp_line
			(start -0.254 -1.1176)
			(end -1.7272 -1.1176)
			(stroke
				(width 0.1524)
				(type default)
			)
			(layer "F.SilkS")
		)
		(fp_line
			(start 0 -0.7366)
			(end -0.254 -1.1176)
			(stroke
				(width 0.1524)
				(type default)
			)
			(layer "F.SilkS")
		)
		(fp_line
			(start 0.254 -1.1176)
			(end 0 -0.7366)
			(stroke
				(width 0.1524)
				(type default)
			)
			(layer "F.SilkS")
		)
		(fp_line
			(start 1.7272 -1.1176)
			(end 0.254 -1.1176)
			(stroke
				(width 0.1524)
				(type default)
			)
			(layer "F.SilkS")
		)
		(fp_line
			(start 1.7272 -1.1176)
			(end 1.7272 1.1176)
			(stroke
				(width 0.1524)
				(type default)
			)
			(layer "F.SilkS")
		)
		(fp_line
			(start 1.7272 1.1176)
			(end -1.7272 1.1176)
			(stroke
				(width 0.1524)
				(type default)
			)
			(layer "F.SilkS")
		)
		(fp_poly
			(pts
				(xy -1.9558 -0.649986) (xy -2.7178 -0.268986) (xy -2.7178 -1.030986)
			)
			(stroke
				(width 0)
				(type default)
			)
			(fill yes)
			(layer "F.SilkS")
		)
		(fp_line
			(start -1.5748 -1.1176)
			(end -1.5748 1.1176)
			(stroke
				(width 0.1)
				(type default)
			)
			(layer "F.Fab")
		)
		(fp_line
			(start -1.5748 1.1176)
			(end 1.5748 1.1176)
			(stroke
				(width 0.1)
				(type default)
			)
			(layer "F.Fab")
		)
		(fp_line
			(start 1.5748 -1.1176)
			(end -1.5748 -1.1176)
			(stroke
				(width 0.1)
				(type default)
			)
			(layer "F.Fab")
		)
		(fp_line
			(start 1.5748 1.1176)
			(end 1.5748 -1.1176)
			(stroke
				(width 0.1)
				(type default)
			)
			(layer "F.Fab")
		)
		(fp_poly
			(pts
				(xy -1.9558 -0.649986) (xy -2.7178 -0.268986) (xy -2.7178 -1.030986)
			)
			(stroke
				(width 0)
				(type default)
			)
			(fill yes)
			(layer "F.Fab")
		)
		(pad "1" smd rect
			(at -0.999998 -0.649986 270)
			(size 0.3556 1.1176)
			(layers "F.Cu" "F.Mask" "F.Paste")
			(net "NIC4_CLK_EN_R_N")
		)
		(pad "2" smd rect
			(at -0.999998 0 270)
			(size 0.3556 1.1176)
			(layers "F.Cu" "F.Mask" "F.Paste")
			(net "GND")
		)
		(pad "3" smd rect
			(at -0.999998 0.649986 270)
			(size 0.3556 1.1176)
			(layers "F.Cu" "F.Mask" "F.Paste")
			(net "NIC5_CLK_EN_R_N")
		)
		(pad "4" smd rect
			(at 0.999998 0.649986 270)
			(size 0.3556 1.1176)
			(layers "F.Cu" "F.Mask" "F.Paste")
			(net "NIC5_CLK_EN_BUF_N")
		)
		(pad "5" smd rect
			(at 0.999998 0 270)
			(size 0.3556 1.1176)
			(layers "F.Cu" "F.Mask" "F.Paste")
			(net "P3V3_AUX")
		)
		(pad "6" smd rect
			(at 0.999998 -0.649986 270)
			(size 0.3556 1.1176)
			(layers "F.Cu" "F.Mask" "F.Paste")
			(net "NIC4_CLK_EN_BUF_N")
		)
	)
	(footprint ""
		(layer "F.Cu")
		(at 367.415318 -239.30102)
		(property "Reference" "U429"
			(at -1.0922 -2.174748 0)
			(unlocked yes)
			(layer "F.SilkS")
			(effects
				(font
					(size 0.7874 0.5842)
					(thickness 0.1524)
				)
				(justify left)
			)
		)
		(property "Value" ""
			(at 0 0 0)
			(layer "F.Fab")
			(effects
				(font
					(size 1.27 1.27)
				)
			)
		)
		(duplicate_pad_numbers_are_jumpers no)
		(fp_line
			(start -1.0414 -1.575054)
			(end -0.254 -1.575054)
			(stroke
				(width 0.1524)
				(type default)
			)
			(layer "F.SilkS")
		)
		(fp_line
			(start -1.0414 1.575054)
			(end -1.0414 -1.575054)
			(stroke
				(width 0.1524)
				(type default)
			)
			(layer "F.SilkS")
		)
		(fp_line
			(start 0 -1.272032)
			(end -0.254 -1.575054)
			(stroke
				(width 0.1524)
				(type default)
			)
			(layer "F.SilkS")
		)
		(fp_line
			(start 0.2286 -1.575054)
			(end 0 -1.272032)
			(stroke
				(width 0.1524)
				(type default)
			)
			(layer "F.SilkS")
		)
		(fp_line
			(start 0.254 -1.575054)
			(end 1.0414 -1.575054)
			(stroke
				(width 0.1524)
				(type default)
			)
			(layer "F.SilkS")
		)
		(fp_line
			(start 1.0414 -1.575054)
			(end 1.0414 1.575054)
			(stroke
				(width 0.1524)
				(type default)
			)
			(layer "F.SilkS")
		)
		(fp_line
			(start 1.0414 1.575054)
			(end -1.0414 1.575054)
			(stroke
				(width 0.1524)
				(type default)
			)
			(layer "F.SilkS")
		)
		(fp_poly
			(pts
				(xy -3.064256 -1.629156) (xy -3.423412 -2.706878) (xy -4.141724 -1.988312)
			)
			(stroke
				(width 0)
				(type default)
			)
			(fill yes)
			(layer "F.SilkS")
		)
		(fp_line
			(start -2.5654 -1.2192)
			(end -1.4478 -1.2192)
			(stroke
				(width 0.1)
				(type default)
			)
			(layer "F.Fab")
		)
		(fp_line
			(start -2.5654 1.2192)
			(end -2.5654 -1.2192)
			(stroke
				(width 0.1)
				(type default)
			)
			(layer "F.Fab")
		)
		(fp_line
			(start -1.4478 -1.5748)
			(end 1.4478 -1.5748)
			(stroke
				(width 0.1)
				(type default)
			)
			(layer "F.Fab")
		)
		(fp_line
			(start -1.4478 -1.2192)
			(end -1.4478 -1.5748)
			(stroke
				(width 0.1)
				(type default)
			)
			(layer "F.Fab")
		)
		(fp_line
			(start -1.4478 1.2192)
			(end -2.5654 1.2192)
			(stroke
				(width 0.1)
				(type default)
			)
			(layer "F.Fab")
		)
		(fp_line
			(start -1.4478 1.5748)
			(end -1.4478 1.2192)
			(stroke
				(width 0.1)
				(type default)
			)
			(layer "F.Fab")
		)
		(fp_line
			(start 1.4478 -1.5748)
			(end 1.4478 -1.2192)
			(stroke
				(width 0.1)
				(type default)
			)
			(layer "F.Fab")
		)
		(fp_line
			(start 1.4478 -1.2192)
			(end 2.5654 -1.2192)
			(stroke
				(width 0.1)
				(type default)
			)
			(layer "F.Fab")
		)
		(fp_line
			(start 1.4478 1.2192)
			(end 1.4478 1.5748)
			(stroke
				(width 0.1)
				(type default)
			)
			(layer "F.Fab")
		)
		(fp_line
			(start 1.4478 1.5748)
			(end -1.4478 1.5748)
			(stroke
				(width 0.1)
				(type default)
			)
			(layer "F.Fab")
		)
		(fp_line
			(start 2.5654 -1.2192)
			(end 2.5654 1.2192)
			(stroke
				(width 0.1)
				(type default)
			)
			(layer "F.Fab")
		)
		(fp_line
			(start 2.5654 1.2192)
			(end 1.4478 1.2192)
			(stroke
				(width 0.1)
				(type default)
			)
			(layer "F.Fab")
		)
		(fp_poly
			(pts
				(xy -2.710688 -0.975106) (xy -3.726688 -1.483106) (xy -3.726688 -0.467106)
			)
			(stroke
				(width 0)
				(type default)
			)
			(fill yes)
			(layer "F.Fab")
		)
		(pad "1" smd rect
			(at -1.849882 -0.975106 270)
			(size 0.3556 1.3208)
			(layers "F.Cu" "F.Mask" "F.Paste")
			(net "PWRGD_P12V_AUX_R1")
		)
		(pad "2" smd rect
			(at -1.849882 -0.32512 270)
			(size 0.3556 1.3208)
			(layers "F.Cu" "F.Mask" "F.Paste")
			(net "PWRGD_P3V3_AUX_BUF")
		)
		(pad "3" smd rect
			(at -1.849882 0.32512 270)
			(size 0.3556 1.3208)
			(layers "F.Cu" "F.Mask" "F.Paste")
			(net "PWRGD_P5V_AUX_R2")
		)
		(pad "4" smd rect
			(at -1.849882 0.975106 270)
			(size 0.3556 1.3208)
			(layers "F.Cu" "F.Mask" "F.Paste")
			(net "GND")
		)
		(pad "5" smd rect
			(at 1.849882 0.975106 270)
			(size 0.3556 1.3208)
			(layers "F.Cu" "F.Mask" "F.Paste")
			(net "PWRGD_P5V_AUX_BUF")
		)
		(pad "6" smd rect
			(at 1.849882 0.32512 270)
			(size 0.3556 1.3208)
			(layers "F.Cu" "F.Mask" "F.Paste")
			(net "PWRGD_P3V3_AUX_R2")
		)
		(pad "7" smd rect
			(at 1.849882 -0.32512 270)
			(size 0.3556 1.3208)
			(layers "F.Cu" "F.Mask" "F.Paste")
			(net "PWRGD_P12V_AUX_BUF")
		)
		(pad "8" smd rect
			(at 1.849882 -0.975106 270)
			(size 0.3556 1.3208)
			(layers "F.Cu" "F.Mask" "F.Paste")
			(net "P3V3_AUX")
		)
	)
)
